# S9S_MB_2U (Grand Teton) — schematic netlist excerpt (pin names and nets, part order shuffled) for the footprints in the layout excerpt that follows; sources: Cadence DE-HDL packaged netlist, KiCad conversion of 03242023_DA0F0TMBIJ0_F0T_Motherboard_J_brd_V01_OCP.brd

PC1183_P0_4  Q_CAP  100NF 50V 10% X7R  pkg C0402  page 272 : A = PVCCFA_EHV_FIVRA_CPU0 ; B = GND
C1944  Q_CAP  0.1UF 25V 10% X7R  pkg 0402  page 217 : A = P3V3_AUX_FPGA_VCCIO2 ; B = GND

(kicad_pcb
	(version 20260206)
	(generator "pcbnew")
	(generator_version "10.0")
	(general
		(thickness 1.6)
		(legacy_teardrops no)
	)
	(paper "A4")
	(title_block
		(title "03242023_DA0F0TMBIJ0_F0T_Motherboard_J_brd_V01_OCP.brd")
		(comment 1 "Grand Teton / footprints 5213-5214 of 6105")
	)
	(layers
		(0 "F.Cu" signal "TOP")
		(4 "In1.Cu" signal "GND")
		(6 "In2.Cu" signal "IN1")
		(8 "In3.Cu" signal "GND1")
		(10 "In4.Cu" signal "IN2")
		(12 "In5.Cu" signal "GND2")
		(14 "In6.Cu" signal "IN3")
		(16 "In7.Cu" signal "GND3")
		(18 "In8.Cu" signal "VCC")
		(20 "In9.Cu" signal "VCC1")
		(22 "In10.Cu" signal "GND4")
		(24 "In11.Cu" signal "IN4")
		(26 "In12.Cu" signal "GND5")
		(28 "In13.Cu" signal "IN5")
		(30 "In14.Cu" signal "GND6")
		(32 "In15.Cu" signal "IN6")
		(34 "In16.Cu" signal "GND7")
		(2 "B.Cu" signal "BOTTOM")
		(9 "F.Adhes" user "F.Adhesive")
		(11 "B.Adhes" user "B.Adhesive")
		(13 "F.Paste" user "Package Geometry/Pastemask Top")
		(15 "B.Paste" user "Package Geometry/Pastemask Bottom")
		(5 "F.SilkS" user "Ref Des/Silkscreen Top")
		(7 "B.SilkS" user "Ref Des/Silkscreen Bottom")
		(1 "F.Mask" user "Board Geometry/Soldermask Top")
		(3 "B.Mask" user "Board Geometry/Soldermask Bottom")
		(17 "Dwgs.User" user "User.Drawings")
		(19 "Cmts.User" user "User.Comments")
		(21 "Eco1.User" user "User.Eco1")
		(23 "Eco2.User" user "User.Eco2")
		(25 "Edge.Cuts" user "Board Geometry/Outline")
		(27 "Margin" user)
		(31 "F.CrtYd" user "Package Geometry/Place Bound Top")
		(29 "B.CrtYd" user "Package Geometry/Place Bound Bottom")
		(35 "F.Fab" user "Ref Des/Assembly Top")
		(33 "B.Fab" user "Ref Des/Assembly Bottom")
	)
	(footprint ""
		(layer "B.Cu")
		(at 293.764208 -354.02139 -90)
		(property "Reference" "PC1183_P0_4"
			(at 0 0 90)
			(layer "B.SilkS")
			(hide yes)
			(effects
				(font
					(size 1.27 1.27)
				)
				(justify mirror)
			)
		)
		(property "Value" ""
			(at 0 0 90)
			(layer "B.Fab")
			(effects
				(font
					(size 1.27 1.27)
				)
				(justify mirror)
			)
		)
		(duplicate_pad_numbers_are_jumpers no)
		(fp_line
			(start -0.7874 0.4064)
			(end 0.7874 0.4064)
			(stroke
				(width 0.1524)
				(type default)
			)
			(layer "B.SilkS")
		)
		(fp_line
			(start 0.7874 0.4064)
			(end 0.7874 -0.4064)
			(stroke
				(width 0.1524)
				(type default)
			)
			(layer "B.SilkS")
		)
		(fp_line
			(start -0.7874 -0.4064)
			(end -0.7874 0.4064)
			(stroke
				(width 0.1524)
				(type default)
			)
			(layer "B.SilkS")
		)
		(fp_line
			(start 0.7874 -0.4064)
			(end -0.7874 -0.4064)
			(stroke
				(width 0.1524)
				(type default)
			)
			(layer "B.SilkS")
		)
		(fp_line
			(start -0.67945 0.3048)
			(end -0.120396 0.3048)
			(stroke
				(width 0.1)
				(type default)
			)
			(layer "B.Fab")
		)
		(fp_line
			(start -0.120396 0.3048)
			(end -0.120396 0.2794)
			(stroke
				(width 0.1)
				(type default)
			)
			(layer "B.Fab")
		)
		(fp_line
			(start 0.12065 0.3048)
			(end 0.67945 0.3048)
			(stroke
				(width 0.1)
				(type default)
			)
			(layer "B.Fab")
		)
		(fp_line
			(start 0.67945 0.3048)
			(end 0.67945 -0.305054)
			(stroke
				(width 0.1)
				(type default)
			)
			(layer "B.Fab")
		)
		(fp_line
			(start -0.120396 0.2794)
			(end 0.12065 0.2794)
			(stroke
				(width 0.1)
				(type default)
			)
			(layer "B.Fab")
		)
		(fp_line
			(start 0.12065 0.2794)
			(end 0.12065 0.3048)
			(stroke
				(width 0.1)
				(type default)
			)
			(layer "B.Fab")
		)
		(fp_line
			(start -0.12065 -0.2794)
			(end -0.12065 -0.3048)
			(stroke
				(width 0.1)
				(type default)
			)
			(layer "B.Fab")
		)
		(fp_line
			(start 0.12065 -0.2794)
			(end -0.12065 -0.2794)
			(stroke
				(width 0.1)
				(type default)
			)
			(layer "B.Fab")
		)
		(fp_line
			(start -0.67945 -0.3048)
			(end -0.67945 0.3048)
			(stroke
				(width 0.1)
				(type default)
			)
			(layer "B.Fab")
		)
		(fp_line
			(start -0.12065 -0.3048)
			(end -0.67945 -0.3048)
			(stroke
				(width 0.1)
				(type default)
			)
			(layer "B.Fab")
		)
		(fp_line
			(start 0.12065 -0.305054)
			(end 0.12065 -0.2794)
			(stroke
				(width 0.1)
				(type default)
			)
			(layer "B.Fab")
		)
		(fp_line
			(start 0.67945 -0.305054)
			(end 0.12065 -0.305054)
			(stroke
				(width 0.1)
				(type default)
			)
			(layer "B.Fab")
		)
		(pad "1" smd circle
			(at 0.40005 0 90)
			(size 0 0)
			(layers "B.Cu" "B.Mask" "B.Paste")
			(net "PVCCFA_EHV_FIVRA_CPU0")
		)
		(pad "2" smd circle
			(at -0.40005 0 90)
			(size 0 0)
			(layers "B.Cu" "B.Mask" "B.Paste")
			(net "GND")
		)
	)
	(footprint ""
		(layer "B.Cu")
		(at 187.88888 -102.707948 180)
		(property "Reference" "C1944"
			(at 0 0 0)
			(layer "B.SilkS")
			(hide yes)
			(effects
				(font
					(size 1.27 1.27)
				)
				(justify mirror)
			)
		)
		(property "Value" ""
			(at 0 0 0)
			(layer "B.Fab")
			(effects
				(font
					(size 1.27 1.27)
				)
				(justify mirror)
			)
		)
		(duplicate_pad_numbers_are_jumpers no)
		(fp_line
			(start 0.7874 0.4064)
			(end 0.7874 -0.4064)
			(stroke
				(width 0.1524)
				(type default)
			)
			(layer "B.SilkS")
		)
		(fp_line
			(start 0.7874 -0.4064)
			(end -0.7874 -0.4064)
			(stroke
				(width 0.1524)
				(type default)
			)
			(layer "B.SilkS")
		)
		(fp_line
			(start -0.7874 0.4064)
			(end 0.7874 0.4064)
			(stroke
				(width 0.1524)
				(type default)
			)
			(layer "B.SilkS")
		)
		(fp_line
			(start -0.7874 -0.4064)
			(end -0.7874 0.4064)
			(stroke
				(width 0.1524)
				(type default)
			)
			(layer "B.SilkS")
		)
		(fp_line
			(start 0.67945 0.3048)
			(end 0.67945 -0.305054)
			(stroke
				(width 0.1)
				(type default)
			)
			(layer "B.Fab")
		)
		(fp_line
			(start 0.67945 -0.305054)
			(end 0.12065 -0.305054)
			(stroke
				(width 0.1)
				(type default)
			)
			(layer "B.Fab")
		)
		(fp_line
			(start 0.12065 0.3048)
			(end 0.67945 0.3048)
			(stroke
				(width 0.1)
				(type default)
			)
			(layer "B.Fab")
		)
		(fp_line
			(start 0.12065 0.2794)
			(end 0.12065 0.3048)
			(stroke
				(width 0.1)
				(type default)
			)
			(layer "B.Fab")
		)
		(fp_line
			(start 0.12065 -0.2794)
			(end -0.12065 -0.2794)
			(stroke
				(width 0.1)
				(type default)
			)
			(layer "B.Fab")
		)
		(fp_line
			(start 0.12065 -0.305054)
			(end 0.12065 -0.2794)
			(stroke
				(width 0.1)
				(type default)
			)
			(layer "B.Fab")
		)
		(fp_line
			(start -0.120396 0.3048)
			(end -0.120396 0.2794)
			(stroke
				(width 0.1)
				(type default)
			)
			(layer "B.Fab")
		)
		(fp_line
			(start -0.120396 0.2794)
			(end 0.12065 0.2794)
			(stroke
				(width 0.1)
				(type default)
			)
			(layer "B.Fab")
		)
		(fp_line
			(start -0.12065 -0.2794)
			(end -0.12065 -0.3048)
			(stroke
				(width 0.1)
				(type default)
			)
			(layer "B.Fab")
		)
		(fp_line
			(start -0.12065 -0.3048)
			(end -0.67945 -0.3048)
			(stroke
				(width 0.1)
				(type default)
			)
			(layer "B.Fab")
		)
		(fp_line
			(start -0.67945 0.3048)
			(end -0.120396 0.3048)
			(stroke
				(width 0.1)
				(type default)
			)
			(layer "B.Fab")
		)
		(fp_line
			(start -0.67945 -0.3048)
			(end -0.67945 0.3048)
			(stroke
				(width 0.1)
				(type default)
			)
			(layer "B.Fab")
		)
		(pad "1" smd circle
			(at 0.40005 0)
			(size 0 0)
			(layers "B.Cu" "B.Mask" "B.Paste")
			(net "P3V3_AUX_FPGA_VCCIO2")
		)
		(pad "2" smd circle
			(at -0.40005 0)
			(size 0 0)
			(layers "B.Cu" "B.Mask" "B.Paste")
			(net "GND")
		)
	)
)
